# T6G (Grand Teton) — schematic netlist excerpt (pin names and nets, part order shuffled) for the footprints in the layout excerpt that follows; sources: Cadence DE-HDL packaged netlist, KiCad conversion of 04192023_DAF0TMB3IC0_F0TG_MB_C_brd_V02_OCP.brd

C6758  Q_CAP  1000PF 50V 5% X7R  pkg 0402  page 360 : A = FM_PWRGD_P1V8_RETIMER_CPU0 ; B = GND
PR2524  Q_RES  10 1% CHIP  pkg 0402LF  page 266 : A = P12V_HSC_SENSE2_N ; B = P12V_HSC_SENSE2_R1_N

(kicad_pcb
	(version 20260206)
	(generator "pcbnew")
	(generator_version "10.0")
	(general
		(thickness 1.6)
		(legacy_teardrops no)
	)
	(paper "A4")
	(title_block
		(title "04192023_DAF0TMB3IC0_F0TG_MB_C_brd_V02_OCP.brd")
		(comment 1 "Grand Teton / footprints 5245-5246 of 8354")
	)
	(layers
		(0 "F.Cu" signal "TOP")
		(4 "In1.Cu" signal "GND")
		(6 "In2.Cu" signal "IN1")
		(8 "In3.Cu" signal "GND1")
		(10 "In4.Cu" signal "IN2")
		(12 "In5.Cu" signal "GND2")
		(14 "In6.Cu" signal "IN3")
		(16 "In7.Cu" signal "GND3")
		(18 "In8.Cu" signal "VCC")
		(20 "In9.Cu" signal "VCC1")
		(22 "In10.Cu" signal "GND4")
		(24 "In11.Cu" signal "IN4")
		(26 "In12.Cu" signal "GND5")
		(28 "In13.Cu" signal "IN5")
		(30 "In14.Cu" signal "GND6")
		(32 "In15.Cu" signal "IN6")
		(34 "In16.Cu" signal "GND7")
		(2 "B.Cu" signal "BOTTOM")
		(9 "F.Adhes" user "F.Adhesive")
		(11 "B.Adhes" user "B.Adhesive")
		(13 "F.Paste" user "Package Geometry/Pastemask Top")
		(15 "B.Paste" user "Package Geometry/Pastemask Bottom")
		(5 "F.SilkS" user "Ref Des/Silkscreen Top")
		(7 "B.SilkS" user "Ref Des/Silkscreen Bottom")
		(1 "F.Mask" user "Board Geometry/Soldermask Top")
		(3 "B.Mask" user "Board Geometry/Soldermask Bottom")
		(17 "Dwgs.User" user "User.Drawings")
		(19 "Cmts.User" user "User.Comments")
		(21 "Eco1.User" user "User.Eco1")
		(23 "Eco2.User" user "User.Eco2")
		(25 "Edge.Cuts" user "Board Geometry/Outline")
		(27 "Margin" user)
		(31 "F.CrtYd" user "Package Geometry/Place Bound Top")
		(29 "B.CrtYd" user "Package Geometry/Place Bound Bottom")
		(35 "F.Fab" user "Ref Des/Assembly Top")
		(33 "B.Fab" user "Ref Des/Assembly Bottom")
	)
	(footprint ""
		(layer "B.Cu")
		(at 238.310928 -289.828732)
		(property "Reference" "C6758"
			(at 0 0 0)
			(layer "B.SilkS")
			(hide yes)
			(effects
				(font
					(size 1.27 1.27)
				)
				(justify mirror)
			)
		)
		(property "Value" ""
			(at 0 0 0)
			(layer "B.Fab")
			(effects
				(font
					(size 1.27 1.27)
				)
				(justify mirror)
			)
		)
		(duplicate_pad_numbers_are_jumpers no)
		(fp_line
			(start -0.7874 -0.4064)
			(end -0.7874 0.4064)
			(stroke
				(width 0.1524)
				(type default)
			)
			(layer "B.SilkS")
		)
		(fp_line
			(start -0.7874 0.4064)
			(end 0.7874 0.4064)
			(stroke
				(width 0.1524)
				(type default)
			)
			(layer "B.SilkS")
		)
		(fp_line
			(start 0.7874 -0.4064)
			(end -0.7874 -0.4064)
			(stroke
				(width 0.1524)
				(type default)
			)
			(layer "B.SilkS")
		)
		(fp_line
			(start 0.7874 0.4064)
			(end 0.7874 -0.4064)
			(stroke
				(width 0.1524)
				(type default)
			)
			(layer "B.SilkS")
		)
		(fp_line
			(start -0.67945 -0.3048)
			(end -0.67945 0.3048)
			(stroke
				(width 0.1)
				(type default)
			)
			(layer "B.Fab")
		)
		(fp_line
			(start -0.67945 0.3048)
			(end -0.120396 0.3048)
			(stroke
				(width 0.1)
				(type default)
			)
			(layer "B.Fab")
		)
		(fp_line
			(start -0.12065 -0.3048)
			(end -0.67945 -0.3048)
			(stroke
				(width 0.1)
				(type default)
			)
			(layer "B.Fab")
		)
		(fp_line
			(start -0.12065 -0.2794)
			(end -0.12065 -0.3048)
			(stroke
				(width 0.1)
				(type default)
			)
			(layer "B.Fab")
		)
		(fp_line
			(start -0.120396 0.2794)
			(end 0.12065 0.2794)
			(stroke
				(width 0.1)
				(type default)
			)
			(layer "B.Fab")
		)
		(fp_line
			(start -0.120396 0.3048)
			(end -0.120396 0.2794)
			(stroke
				(width 0.1)
				(type default)
			)
			(layer "B.Fab")
		)
		(fp_line
			(start 0.12065 -0.305054)
			(end 0.12065 -0.2794)
			(stroke
				(width 0.1)
				(type default)
			)
			(layer "B.Fab")
		)
		(fp_line
			(start 0.12065 -0.2794)
			(end -0.12065 -0.2794)
			(stroke
				(width 0.1)
				(type default)
			)
			(layer "B.Fab")
		)
		(fp_line
			(start 0.12065 0.2794)
			(end 0.12065 0.3048)
			(stroke
				(width 0.1)
				(type default)
			)
			(layer "B.Fab")
		)
		(fp_line
			(start 0.12065 0.3048)
			(end 0.67945 0.3048)
			(stroke
				(width 0.1)
				(type default)
			)
			(layer "B.Fab")
		)
		(fp_line
			(start 0.67945 -0.305054)
			(end 0.12065 -0.305054)
			(stroke
				(width 0.1)
				(type default)
			)
			(layer "B.Fab")
		)
		(fp_line
			(start 0.67945 0.3048)
			(end 0.67945 -0.305054)
			(stroke
				(width 0.1)
				(type default)
			)
			(layer "B.Fab")
		)
		(pad "1" smd circle
			(at 0.40005 0 180)
			(size 0 0)
			(layers "B.Cu" "B.Mask" "B.Paste")
			(net "FM_PWRGD_P1V8_RETIMER_CPU0")
		)
		(pad "2" smd circle
			(at -0.40005 0 180)
			(size 0 0)
			(layers "B.Cu" "B.Mask" "B.Paste")
			(net "GND")
		)
	)
	(footprint ""
		(layer "B.Cu")
		(at 206.429356 -378.682504 180)
		(property "Reference" "PR2524"
			(at 0 0 0)
			(layer "B.SilkS")
			(hide yes)
			(effects
				(font
					(size 1.27 1.27)
				)
				(justify mirror)
			)
		)
		(property "Value" ""
			(at 0 0 0)
			(layer "B.Fab")
			(effects
				(font
					(size 1.27 1.27)
				)
				(justify mirror)
			)
		)
		(duplicate_pad_numbers_are_jumpers no)
		(fp_line
			(start 0.7874 0.4064)
			(end 0.7874 -0.4064)
			(stroke
				(width 0.1524)
				(type default)
			)
			(layer "B.SilkS")
		)
		(fp_line
			(start 0.7874 -0.4064)
			(end -0.7874 -0.4064)
			(stroke
				(width 0.1524)
				(type default)
			)
			(layer "B.SilkS")
		)
		(fp_line
			(start -0.7874 0.4064)
			(end 0.7874 0.4064)
			(stroke
				(width 0.1524)
				(type default)
			)
			(layer "B.SilkS")
		)
		(fp_line
			(start -0.7874 -0.4064)
			(end -0.7874 0.4064)
			(stroke
				(width 0.1524)
				(type default)
			)
			(layer "B.SilkS")
		)
		(fp_line
			(start 0.67945 0.3048)
			(end 0.67945 -0.305054)
			(stroke
				(width 0.1)
				(type default)
			)
			(layer "B.Fab")
		)
		(fp_line
			(start 0.67945 -0.305054)
			(end 0.12065 -0.305054)
			(stroke
				(width 0.1)
				(type default)
			)
			(layer "B.Fab")
		)
		(fp_line
			(start 0.12065 0.3048)
			(end 0.67945 0.3048)
			(stroke
				(width 0.1)
				(type default)
			)
			(layer "B.Fab")
		)
		(fp_line
			(start 0.12065 0.2794)
			(end 0.12065 0.3048)
			(stroke
				(width 0.1)
				(type default)
			)
			(layer "B.Fab")
		)
		(fp_line
			(start 0.12065 -0.2794)
			(end -0.12065 -0.2794)
			(stroke
				(width 0.1)
				(type default)
			)
			(layer "B.Fab")
		)
		(fp_line
			(start 0.12065 -0.305054)
			(end 0.12065 -0.2794)
			(stroke
				(width 0.1)
				(type default)
			)
			(layer "B.Fab")
		)
		(fp_line
			(start -0.120396 0.3048)
			(end -0.120396 0.2794)
			(stroke
				(width 0.1)
				(type default)
			)
			(layer "B.Fab")
		)
		(fp_line
			(start -0.120396 0.2794)
			(end 0.12065 0.2794)
			(stroke
				(width 0.1)
				(type default)
			)
			(layer "B.Fab")
		)
		(fp_line
			(start -0.12065 -0.2794)
			(end -0.12065 -0.3048)
			(stroke
				(width 0.1)
				(type default)
			)
			(layer "B.Fab")
		)
		(fp_line
			(start -0.12065 -0.3048)
			(end -0.67945 -0.3048)
			(stroke
				(width 0.1)
				(type default)
			)
			(layer "B.Fab")
		)
		(fp_line
			(start -0.67945 0.3048)
			(end -0.120396 0.3048)
			(stroke
				(width 0.1)
				(type default)
			)
			(layer "B.Fab")
		)
		(fp_line
			(start -0.67945 -0.3048)
			(end -0.67945 0.3048)
			(stroke
				(width 0.1)
				(type default)
			)
			(layer "B.Fab")
		)
		(pad "1" smd circle
			(at 0.40005 0)
			(size 0 0)
			(layers "B.Cu" "B.Mask" "B.Paste")
			(net "P12V_HSC_SENSE2_N")
		)
		(pad "2" smd circle
			(at -0.40005 0)
			(size 0 0)
			(layers "B.Cu" "B.Mask" "B.Paste")
			(net "P12V_HSC_SENSE2_R1_N")
		)
	)
)
